# T6G (Grand Teton) — schematic netlist excerpt (pin names and nets, part order shuffled) for the footprints in the layout excerpt that follows; sources: Cadence DE-HDL packaged netlist, KiCad conversion of 04192023_DAF0TMB3IC0_F0TG_MB_C_brd_V02_OCP.brd

PC6543  Q_CAP  100NF 50V 10% X7R  pkg C0402  page 364 : A = P0V9_RETIMER_CPU1_VCC ; B = GND
R9027  Q_RES  100K 1% CHIP  pkg 0402LF  page 85 : A = P3V3_AUX ; B = IRQ_HSC_FAULT_BUF_N

(kicad_pcb
	(version 20260206)
	(generator "pcbnew")
	(generator_version "10.0")
	(general
		(thickness 1.6)
		(legacy_teardrops no)
	)
	(paper "A4")
	(title_block
		(title "04192023_DAF0TMB3IC0_F0TG_MB_C_brd_V02_OCP.brd")
		(comment 1 "Grand Teton / footprints 1134-1135 of 8354")
	)
	(layers
		(0 "F.Cu" signal "TOP")
		(4 "In1.Cu" signal "GND")
		(6 "In2.Cu" signal "IN1")
		(8 "In3.Cu" signal "GND1")
		(10 "In4.Cu" signal "IN2")
		(12 "In5.Cu" signal "GND2")
		(14 "In6.Cu" signal "IN3")
		(16 "In7.Cu" signal "GND3")
		(18 "In8.Cu" signal "VCC")
		(20 "In9.Cu" signal "VCC1")
		(22 "In10.Cu" signal "GND4")
		(24 "In11.Cu" signal "IN4")
		(26 "In12.Cu" signal "GND5")
		(28 "In13.Cu" signal "IN5")
		(30 "In14.Cu" signal "GND6")
		(32 "In15.Cu" signal "IN6")
		(34 "In16.Cu" signal "GND7")
		(2 "B.Cu" signal "BOTTOM")
		(9 "F.Adhes" user "F.Adhesive")
		(11 "B.Adhes" user "B.Adhesive")
		(13 "F.Paste" user "Package Geometry/Pastemask Top")
		(15 "B.Paste" user "Package Geometry/Pastemask Bottom")
		(5 "F.SilkS" user "Ref Des/Silkscreen Top")
		(7 "B.SilkS" user "Ref Des/Silkscreen Bottom")
		(1 "F.Mask" user "Board Geometry/Soldermask Top")
		(3 "B.Mask" user "Board Geometry/Soldermask Bottom")
		(17 "Dwgs.User" user "User.Drawings")
		(19 "Cmts.User" user "User.Comments")
		(21 "Eco1.User" user "User.Eco1")
		(23 "Eco2.User" user "User.Eco2")
		(25 "Edge.Cuts" user "Board Geometry/Outline")
		(27 "Margin" user)
		(31 "F.CrtYd" user "Package Geometry/Place Bound Top")
		(29 "B.CrtYd" user "Package Geometry/Place Bound Bottom")
		(35 "F.Fab" user "Ref Des/Assembly Top")
		(33 "B.Fab" user "Ref Des/Assembly Bottom")
	)
	(footprint ""
		(layer "F.Cu")
		(at 10.066782 -407.262584 180)
		(property "Reference" "PC6543"
			(at 0 0 180)
			(layer "F.SilkS")
			(hide yes)
			(effects
				(font
					(size 1.27 1.27)
				)
			)
		)
		(property "Value" ""
			(at 0 0 180)
			(layer "F.Fab")
			(effects
				(font
					(size 1.27 1.27)
				)
			)
		)
		(duplicate_pad_numbers_are_jumpers no)
		(fp_line
			(start 0.7874 0.4064)
			(end -0.7874 0.4064)
			(stroke
				(width 0.1524)
				(type default)
			)
			(layer "F.SilkS")
		)
		(fp_line
			(start 0.7874 -0.4064)
			(end 0.7874 0.4064)
			(stroke
				(width 0.1524)
				(type default)
			)
			(layer "F.SilkS")
		)
		(fp_line
			(start -0.7874 0.4064)
			(end -0.7874 -0.4064)
			(stroke
				(width 0.1524)
				(type default)
			)
			(layer "F.SilkS")
		)
		(fp_line
			(start -0.7874 -0.4064)
			(end 0.7874 -0.4064)
			(stroke
				(width 0.1524)
				(type default)
			)
			(layer "F.SilkS")
		)
		(fp_line
			(start 0.67945 0.3048)
			(end 0.120396 0.3048)
			(stroke
				(width 0.1)
				(type default)
			)
			(layer "F.Fab")
		)
		(fp_line
			(start 0.67945 -0.3048)
			(end 0.67945 0.3048)
			(stroke
				(width 0.1)
				(type default)
			)
			(layer "F.Fab")
		)
		(fp_line
			(start 0.12065 -0.2794)
			(end 0.12065 -0.3048)
			(stroke
				(width 0.1)
				(type default)
			)
			(layer "F.Fab")
		)
		(fp_line
			(start 0.12065 -0.3048)
			(end 0.67945 -0.3048)
			(stroke
				(width 0.1)
				(type default)
			)
			(layer "F.Fab")
		)
		(fp_line
			(start 0.120396 0.3048)
			(end 0.120396 0.2794)
			(stroke
				(width 0.1)
				(type default)
			)
			(layer "F.Fab")
		)
		(fp_line
			(start 0.120396 0.2794)
			(end -0.12065 0.2794)
			(stroke
				(width 0.1)
				(type default)
			)
			(layer "F.Fab")
		)
		(fp_line
			(start -0.12065 0.3048)
			(end -0.67945 0.3048)
			(stroke
				(width 0.1)
				(type default)
			)
			(layer "F.Fab")
		)
		(fp_line
			(start -0.12065 0.2794)
			(end -0.12065 0.3048)
			(stroke
				(width 0.1)
				(type default)
			)
			(layer "F.Fab")
		)
		(fp_line
			(start -0.12065 -0.2794)
			(end 0.12065 -0.2794)
			(stroke
				(width 0.1)
				(type default)
			)
			(layer "F.Fab")
		)
		(fp_line
			(start -0.12065 -0.305054)
			(end -0.12065 -0.2794)
			(stroke
				(width 0.1)
				(type default)
			)
			(layer "F.Fab")
		)
		(fp_line
			(start -0.67945 0.3048)
			(end -0.67945 -0.305054)
			(stroke
				(width 0.1)
				(type default)
			)
			(layer "F.Fab")
		)
		(fp_line
			(start -0.67945 -0.305054)
			(end -0.12065 -0.305054)
			(stroke
				(width 0.1)
				(type default)
			)
			(layer "F.Fab")
		)
		(pad "1" smd circle
			(at -0.40005 0 180)
			(size 0 0)
			(layers "F.Cu" "F.Mask" "F.Paste")
			(net "P0V9_RETIMER_CPU1_VCC")
		)
		(pad "2" smd circle
			(at 0.40005 0 180)
			(size 0 0)
			(layers "F.Cu" "F.Mask" "F.Paste")
			(net "GND")
		)
	)
	(footprint ""
		(layer "F.Cu")
		(at 164.719 -107.315 180)
		(property "Reference" "R9027"
			(at 0 0 180)
			(layer "F.SilkS")
			(hide yes)
			(effects
				(font
					(size 1.27 1.27)
				)
			)
		)
		(property "Value" ""
			(at 0 0 180)
			(layer "F.Fab")
			(effects
				(font
					(size 1.27 1.27)
				)
			)
		)
		(duplicate_pad_numbers_are_jumpers no)
		(fp_line
			(start 0.7874 0.4064)
			(end -0.7874 0.4064)
			(stroke
				(width 0.1524)
				(type default)
			)
			(layer "F.SilkS")
		)
		(fp_line
			(start 0.7874 -0.4064)
			(end 0.7874 0.4064)
			(stroke
				(width 0.1524)
				(type default)
			)
			(layer "F.SilkS")
		)
		(fp_line
			(start -0.7874 0.4064)
			(end -0.7874 -0.4064)
			(stroke
				(width 0.1524)
				(type default)
			)
			(layer "F.SilkS")
		)
		(fp_line
			(start -0.7874 -0.4064)
			(end 0.7874 -0.4064)
			(stroke
				(width 0.1524)
				(type default)
			)
			(layer "F.SilkS")
		)
		(fp_line
			(start 0.67945 0.3048)
			(end 0.120396 0.3048)
			(stroke
				(width 0.1)
				(type default)
			)
			(layer "F.Fab")
		)
		(fp_line
			(start 0.67945 -0.3048)
			(end 0.67945 0.3048)
			(stroke
				(width 0.1)
				(type default)
			)
			(layer "F.Fab")
		)
		(fp_line
			(start 0.12065 -0.2794)
			(end 0.12065 -0.3048)
			(stroke
				(width 0.1)
				(type default)
			)
			(layer "F.Fab")
		)
		(fp_line
			(start 0.12065 -0.3048)
			(end 0.67945 -0.3048)
			(stroke
				(width 0.1)
				(type default)
			)
			(layer "F.Fab")
		)
		(fp_line
			(start 0.120396 0.3048)
			(end 0.120396 0.2794)
			(stroke
				(width 0.1)
				(type default)
			)
			(layer "F.Fab")
		)
		(fp_line
			(start 0.120396 0.2794)
			(end -0.12065 0.2794)
			(stroke
				(width 0.1)
				(type default)
			)
			(layer "F.Fab")
		)
		(fp_line
			(start -0.12065 0.3048)
			(end -0.67945 0.3048)
			(stroke
				(width 0.1)
				(type default)
			)
			(layer "F.Fab")
		)
		(fp_line
			(start -0.12065 0.2794)
			(end -0.12065 0.3048)
			(stroke
				(width 0.1)
				(type default)
			)
			(layer "F.Fab")
		)
		(fp_line
			(start -0.12065 -0.2794)
			(end 0.12065 -0.2794)
			(stroke
				(width 0.1)
				(type default)
			)
			(layer "F.Fab")
		)
		(fp_line
			(start -0.12065 -0.305054)
			(end -0.12065 -0.2794)
			(stroke
				(width 0.1)
				(type default)
			)
			(layer "F.Fab")
		)
		(fp_line
			(start -0.67945 0.3048)
			(end -0.67945 -0.305054)
			(stroke
				(width 0.1)
				(type default)
			)
			(layer "F.Fab")
		)
		(fp_line
			(start -0.67945 -0.305054)
			(end -0.12065 -0.305054)
			(stroke
				(width 0.1)
				(type default)
			)
			(layer "F.Fab")
		)
		(pad "1" smd circle
			(at -0.40005 0 180)
			(size 0 0)
			(layers "F.Cu" "F.Mask" "F.Paste")
			(net "P3V3_AUX")
		)
		(pad "2" smd circle
			(at 0.40005 0 180)
			(size 0 0)
			(layers "F.Cu" "F.Mask" "F.Paste")
			(net "IRQ_HSC_FAULT_BUF_N")
		)
	)
)
